# T6G (Grand Teton) — schematic netlist excerpt (pin names and nets, part order shuffled) for the footprints in the layout excerpt that follows; sources: Cadence DE-HDL packaged netlist, KiCad conversion of 04192023_DAF0TMB3IC0_F0TG_MB_C_brd_V02_OCP.brd

J69  SCONN288_DDR506112002KQ  IO  pkg DDR288S_1-1VXC  page 93
  VIN_BULK0  = P12V_MEM_CPU0
  RFU0  = NC
  VIN_MGMT  = P3V3_AUX
  HSCL  = I3C_SPD_DDRH_CPU0_SCL
  HSDA  = I3C_SPD_DDRH_CPU0_SDA
  VSS0  = GND
  DQ0_A  = M_H_CPU0_SA_DQ<0>
  VSS1  = GND
  DQ1_A  = M_H_CPU0_SA_DQ<1>
  VSS2  = GND
  DQS0_A_T  = M_H_CPU0_SA_DQS_DP<0>
  DQS0_A_C  = M_H_CPU0_SA_DQS_DN<0>
  VSS3  = GND
  DQ4_A  = M_H_CPU0_SA_DQ<4>
  VSS4  = GND
  DQ5_A  = M_H_CPU0_SA_DQ<5>
  VSS5  = GND
  DQ8_A  = M_H_CPU0_SA_DQ<8>
  VSS6  = GND
  DQ9_A  = M_H_CPU0_SA_DQ<9>
  VSS7  = GND
  DQS1_A_T  = M_H_CPU0_SA_DQS_DP<1>
  DQS1_A_C  = M_H_CPU0_SA_DQS_DN<1>
  VSS8  = GND
  DQ12_A  = M_H_CPU0_SA_DQ<12>
  VSS9  = GND
  DQ13_A  = M_H_CPU0_SA_DQ<13>
  VSS10  = GND
  DQ16_A  = M_H_CPU0_SA_DQ<16>
  VSS11  = GND
  DQ17_A  = M_H_CPU0_SA_DQ<17>
  VSS12  = GND
  DQS2_A_T  = M_H_CPU0_SA_DQS_DP<2>
  DQS2_A_C  = M_H_CPU0_SA_DQS_DN<2>
  VSS13  = GND
  DQ20_A  = M_H_CPU0_SA_DQ<20>
  VSS14  = GND
  DQ21_A  = M_H_CPU0_SA_DQ<21>
  VSS15  = GND
  DQ24_A  = M_H_CPU0_SA_DQ<24>
  VSS16  = GND
  DQ25_A  = M_H_CPU0_SA_DQ<25>
  VSS17  = GND
  DQS3_A_T  = M_H_CPU0_SA_DQS_DP<3>
  DQS3_A_C  = M_H_CPU0_SA_DQS_DN<3>
  VSS18  = GND
  DQ28_A  = M_H_CPU0_SA_DQ<28>
  VSS19  = GND
  DQ29_A  = M_H_CPU0_SA_DQ<29>
  VSS20  = GND
  CB0_A  = M_H_CPU0_SA_CB<0>
  VSS21  = GND
  CB1_A  = M_H_CPU0_SA_CB<1>
  VSS22  = GND
  DQS4_A_T  = M_H_CPU0_SA_DQS_DP<4>
  DQS4_A_C  = M_H_CPU0_SA_DQS_DN<4>
  VSS23  = GND
  CB4_A  = M_H_CPU0_SA_CB<4>
  VSS24  = GND
  CB5_A  = M_H_CPU0_SA_CB<5>
  VSS25  = GND
  ALERT_N  = M_H_CPU0_ALERT_N
  VSS26  = GND
  CS0_A_N  = M_H_CPU0_SA_CS_N<0>
  VSS27  = GND
  CA0_A  = M_H_CPU0_SA_CA<0>
  VSS28  = GND
  CA2_A  = M_H_CPU0_SA_CA<2>
  VSS29  = GND
  CA4_A  = M_H_CPU0_SA_CA<4>
  VSS30  = GND
  CA6_A  = M_H_CPU0_SA_CA<6>
  VSS31  = GND
  PAR_A  = M_H_CPU0_SA_PAR
  VSS32  = GND
  CA0_B  = M_H_CPU0_SB_CA<0>
  VSS33  = GND
  CA2_B  = M_H_CPU0_SB_CA<2>
  VSS34  = GND
  CA4_B  = M_H_CPU0_SB_CA<4>
  VSS35  = GND
  CA6_B  = M_H_CPU0_SB_CA<6>
  VSS36  = GND
  CS0_B_N  = M_H_CPU0_SB_CS_N<0>
  VSS37  = GND
  \lbd||rsp_a_n\  = M_H_CPU0_SA_RSP<0>
  \lbs||rsp_b_n\  = M_H_CPU0_SB_RSP<0>
  VSS38  = GND
  CB4_B  = M_H_CPU0_SB_CB<4>
  VSS39  = GND
  CB5_B  = M_H_CPU0_SB_CB<5>
  VSS40  = GND
  \dqs9_b_t||tdqs9_b_t||dbi4_b_n\  = M_H_CPU0_SB_DQS_DP<9>
  \dqs9_b_c||tdqs9_b_c\  = M_H_CPU0_SB_DQS_DN<9>
  VSS41  = GND
  CB0_B  = M_H_CPU0_SB_CB<0>
  VSS42  = GND
  CB1_B  = M_H_CPU0_SB_CB<1>
  VSS43  = GND
  DQ0_B  = M_H_CPU0_SB_DQ<0>
  VSS44  = GND
  DQ1_B  = M_H_CPU0_SB_DQ<1>
  VSS45  = GND
  DQS0_B_T  = M_H_CPU0_SB_DQS_DP<0>
  DQS0_B_C  = M_H_CPU0_SB_DQS_DN<0>
  VSS46  = GND
  DQ4_B  = M_H_CPU0_SB_DQ<4>
  VSS47  = GND
  DQ5_B  = M_H_CPU0_SB_DQ<5>
  VSS48  = GND
  DQ8_B  = M_H_CPU0_SB_DQ<8>
  VSS49  = GND
  DQ9_B  = M_H_CPU0_SB_DQ<9>
  VSS50  = GND
  DQS1_B_T  = M_H_CPU0_SB_DQS_DP<1>
  DQS1_B_C  = M_H_CPU0_SB_DQS_DN<1>
  VSS51  = GND
  DQ12_B  = M_H_CPU0_SB_DQ<12>
  VSS52  = GND
  DQ13_B  = M_H_CPU0_SB_DQ<13>
  VSS53  = GND
  DQ16_B  = M_H_CPU0_SB_DQ<16>
  VSS54  = GND
  DQ17_B  = M_H_CPU0_SB_DQ<17>
  VSS55  = GND
  DQS2_B_T  = M_H_CPU0_SB_DQS_DP<2>
  DQS2_B_C  = M_H_CPU0_SB_DQS_DN<2>
  VSS56  = GND
  DQ20_B  = M_H_CPU0_SB_DQ<20>
  VSS57  = GND
  DQ21_B  = M_H_CPU0_SB_DQ<21>
  VSS58  = GND
  DQ24_B  = M_H_CPU0_SB_DQ<24>
  VSS59  = GND
  DQ25_B  = M_H_CPU0_SB_DQ<25>
  VSS60  = GND
  DQS3_B_T  = M_H_CPU0_SB_DQS_DP<3>
  DQS3_B_C  = M_H_CPU0_SB_DQS_DN<3>
  VSS61  = GND
  DQ28_B  = M_H_CPU0_SB_DQ<28>
  VSS62  = GND
  DQ29_B  = M_H_CPU0_SB_DQ<29>
  VSS63  = GND
  RFU1  = NC
  VIN_BULK1  = P12V_MEM_CPU0
  VIN_BULK2  = P12V_MEM_CPU0
  \pwr_good||fail_n\  = PWRGD_CHH_CPU0_DIMM
  HAS  = PD_CHH_CPU0_DIMM_SAA
  RFU2  = NC
  RFU3  = NC
  VSS64  = GND
  DQ2_A  = M_H_CPU0_SA_DQ<2>
  VSS65  = GND
  DQ3_A  = M_H_CPU0_SA_DQ<3>
  VSS66  = GND
  \dqs5_a_c||tdqs5_a_c||dqs5_a_t||tdqs5_a_t\  = M_H_CPU0_SA_DQS_DN<5>
  \dqs5_a_t||tdqs5_a_t\  = M_H_CPU0_SA_DQS_DP<5>
  VSS67  = GND
  DQ6_A  = M_H_CPU0_SA_DQ<6>
  VSS68  = GND
  DQ7_A  = M_H_CPU0_SA_DQ<7>
  VSS69  = GND
  DQ10_A  = M_H_CPU0_SA_DQ<10>
  VSS70  = GND
  DQ11_A  = M_H_CPU0_SA_DQ<11>
  VSS71  = GND
  \dqs6_a_c||tdqs6_a_c||dqs6_a_t||tdqs6_a_t\  = M_H_CPU0_SA_DQS_DN<6>
  \dqs6_a_t||tdqs6_a_t\  = M_H_CPU0_SA_DQS_DP<6>
  VSS72  = GND
  DQ14_A  = M_H_CPU0_SA_DQ<14>
  VSS73  = GND
  DQ15_A  = M_H_CPU0_SA_DQ<15>
  VSS74  = GND
  DQ18_A  = M_H_CPU0_SA_DQ<18>
  VSS75  = GND
  DQ19_A  = M_H_CPU0_SA_DQ<19>
  VSS76  = GND
  \dqs7_a_c||tdqs7_a_c\  = M_H_CPU0_SA_DQS_DN<7>
  \dqs7_a_t||tdqs7_a_t\  = M_H_CPU0_SA_DQS_DP<7>
  VSS77  = GND
  DQ22_A  = M_H_CPU0_SA_DQ<22>
  VSS78  = GND
  DQ23_A  = M_H_CPU0_SA_DQ<23>
  VSS79  = GND
  DQ26_A  = M_H_CPU0_SA_DQ<26>
  VSS80  = GND
  DQ27_A  = M_H_CPU0_SA_DQ<27>
  VSS81  = GND
  \dqs8_a_c||tdqs8_a_c\  = M_H_CPU0_SA_DQS_DN<8>
  \dqs8_a_t||tdqs8_a_t\  = M_H_CPU0_SA_DQS_DP<8>
  VSS82  = GND
  DQ30_A  = M_H_CPU0_SA_DQ<30>
  VSS83  = GND
  DQ31_A  = M_H_CPU0_SA_DQ<31>
  VSS84  = GND
  CB2_A  = M_H_CPU0_SA_CB<2>
  VSS85  = GND
  CB3_A  = M_H_CPU0_SA_CB<3>
  VSS86  = GND
  \dqs9_a_c||tdqs9_a_c\  = M_H_CPU0_SA_DQS_DN<9>
  \dqs9_a_t||tdqs9_a_t\  = M_H_CPU0_SA_DQS_DP<9>
  VSS87  = GND
  CB6_A  = M_H_CPU0_SA_CB<6>
  VSS88  = GND
  CB7_A  = M_H_CPU0_SA_CB<7>
  VSS89  = GND
  RESET_N  = M_H_CPU0_RESET_N
  VSS90  = GND
  CS1_A_N  = M_H_CPU0_SA_CS_N<1>
  VSS91  = GND
  CA1_A  = M_H_CPU0_SA_CA<1>
  VSS92  = GND
  CA3_A  = M_H_CPU0_SA_CA<3>
  VSS93  = GND
  CA5_A  = M_H_CPU0_SA_CA<5>
  VSS94  = GND
  CK_T  = M_H_CPU0_CLK_DP<0>
  CK_C  = M_H_CPU0_CLK_DN<0>
  VSS95  = GND
  RFU4  = NC
  CA1_B  = M_H_CPU0_SB_CA<1>
  VSS96  = GND
  CA3_B  = M_H_CPU0_SB_CA<3>
  VSS97  = GND
  CA5_B  = M_H_CPU0_SB_CA<5>
  VSS98  = GND
  PAR_B  = M_H_CPU0_SB_PAR
  VSS99  = GND
  CS1_B_N  = M_H_CPU0_SB_CS_N<1>
  VSS100  = GND
  RFU5  = NC
  RFU6  = NC
  VSS101  = GND
  CB6_B  = M_H_CPU0_SB_CB<6>
  VSS102  = GND
  CB7_B  = M_H_CPU0_SB_CB<7>
  VSS103  = GND
  DQS4_B_C  = M_H_CPU0_SB_DQS_DN<4>
  DQS4_B_T  = M_H_CPU0_SB_DQS_DP<4>
  VSS104  = GND
  CB2_B  = M_H_CPU0_SB_CB<2>
  VSS105  = GND
  CB3_B  = M_H_CPU0_SB_CB<3>
  VSS106  = GND
  DQ2_B  = M_H_CPU0_SB_DQ<2>
  VSS107  = GND
  DQ3_B  = M_H_CPU0_SB_DQ<3>
  VSS108  = GND
  \dqs5_b_c||tdqs5_b_c\  = M_H_CPU0_SB_DQS_DN<5>
  \dqs5_b_t||tdqs5_b_t\  = M_H_CPU0_SB_DQS_DP<5>
  VSS109  = GND
  DQ6_B  = M_H_CPU0_SB_DQ<6>
  VSS110  = GND
  DQ7_B  = M_H_CPU0_SB_DQ<7>
  VSS111  = GND
  DQ10_B  = M_H_CPU0_SB_DQ<10>
  VSS112  = GND
  DQ11_B  = M_H_CPU0_SB_DQ<11>
  VSS113  = GND
  \dqs6_b_c||tdqs6_b_c\  = M_H_CPU0_SB_DQS_DN<6>
  \dqs6_b_t||tdqs6_b_t\  = M_H_CPU0_SB_DQS_DP<6>
  VSS114  = GND
  DQ14_B  = M_H_CPU0_SB_DQ<14>
  VSS115  = GND
  DQ15_B  = M_H_CPU0_SB_DQ<15>
  VSS116  = GND
  DQ18_B  = M_H_CPU0_SB_DQ<18>
  VSS117  = GND
  DQ19_B  = M_H_CPU0_SB_DQ<19>
  VSS118  = GND
  \dqs7_b_c||tdqs7_b_c\  = M_H_CPU0_SB_DQS_DN<7>
  \dqs7_b_t||tdqs7_b_t\  = M_H_CPU0_SB_DQS_DP<7>
  VSS119  = GND
  DQ22_B  = M_H_CPU0_SB_DQ<22>
  VSS120  = GND
  DQ23_B  = M_H_CPU0_SB_DQ<23>
  VSS121  = GND
  DQ26_B  = M_H_CPU0_SB_DQ<26>
  VSS122  = GND
  DQ27_B  = M_H_CPU0_SB_DQ<27>
  VSS123  = GND
  \dqs8_b_c||tdqs8_b_c\  = M_H_CPU0_SB_DQS_DN<8>
  \dqs8_b_t||tdqs8_b_t\  = M_H_CPU0_SB_DQS_DP<8>
  VSS124  = GND
  DQ30_B  = M_H_CPU0_SB_DQ<30>
  VSS125  = GND
  DQ31_B  = M_H_CPU0_SB_DQ<31>
  VSS126  = GND
  G1  = GND
  G2  = GND
  G3  = GND

(kicad_pcb
	(version 20260206)
	(generator "pcbnew")
	(generator_version "10.0")
	(general
		(thickness 1.6)
		(legacy_teardrops no)
	)
	(paper "A4")
	(title_block
		(title "04192023_DAF0TMB3IC0_F0TG_MB_C_brd_V02_OCP.brd")
		(comment 1 "Grand Teton / footprint 2335 of 8354 (J69), pads 185-230 of 291")
	)
	(layers
		(0 "F.Cu" signal "TOP")
		(4 "In1.Cu" signal "GND")
		(6 "In2.Cu" signal "IN1")
		(8 "In3.Cu" signal "GND1")
		(10 "In4.Cu" signal "IN2")
		(12 "In5.Cu" signal "GND2")
		(14 "In6.Cu" signal "IN3")
		(16 "In7.Cu" signal "GND3")
		(18 "In8.Cu" signal "VCC")
		(20 "In9.Cu" signal "VCC1")
		(22 "In10.Cu" signal "GND4")
		(24 "In11.Cu" signal "IN4")
		(26 "In12.Cu" signal "GND5")
		(28 "In13.Cu" signal "IN5")
		(30 "In14.Cu" signal "GND6")
		(32 "In15.Cu" signal "IN6")
		(34 "In16.Cu" signal "GND7")
		(2 "B.Cu" signal "BOTTOM")
		(9 "F.Adhes" user "F.Adhesive")
		(11 "B.Adhes" user "B.Adhesive")
		(13 "F.Paste" user "Package Geometry/Pastemask Top")
		(15 "B.Paste" user "Package Geometry/Pastemask Bottom")
		(5 "F.SilkS" user "Ref Des/Silkscreen Top")
		(7 "B.SilkS" user "Ref Des/Silkscreen Bottom")
		(1 "F.Mask" user "Board Geometry/Soldermask Top")
		(3 "B.Mask" user "Board Geometry/Soldermask Bottom")
		(17 "Dwgs.User" user "User.Drawings")
		(19 "Cmts.User" user "User.Comments")
		(21 "Eco1.User" user "User.Eco1")
		(23 "Eco2.User" user "User.Eco2")
		(25 "Edge.Cuts" user "Board Geometry/Outline")
		(27 "Margin" user)
		(31 "F.CrtYd" user "Package Geometry/Place Bound Top")
		(29 "B.CrtYd" user "Package Geometry/Place Bound Bottom")
		(35 "F.Fab" user "Ref Des/Assembly Top")
		(33 "B.Fab" user "Ref Des/Assembly Bottom")
	)
	(footprint ""
		(layer "F.Cu")
		(at 421.962072 -255.560068 180)
		(property "Reference" "J69"
			(at 3.448304 81.947512 0)
			(unlocked yes)
			(layer "F.SilkS")
			(effects
				(font
					(size 0.7874 0.5842)
					(thickness 0.1524)
				)
			)
		)
		(property "Value" ""
			(at 0 0 180)
			(layer "F.Fab")
			(effects
				(font
					(size 1.27 1.27)
				)
			)
		)
		(duplicate_pad_numbers_are_jumpers no)
		(pad "185" smd rect
			(at 2.050034 -29.325062 90)
			(size 0.519938 1.4986)
			(layers "F.Cu" "F.Mask" "F.Paste")
			(net "M_H_CPU0_SA_DQ<26>")
		)
		(pad "186" smd rect
			(at 2.050034 -28.474924 90)
			(size 0.519938 1.4986)
			(layers "F.Cu" "F.Mask" "F.Paste")
			(net "GND")
		)
		(pad "187" smd rect
			(at 2.050034 -27.62504 90)
			(size 0.519938 1.4986)
			(layers "F.Cu" "F.Mask" "F.Paste")
			(net "M_H_CPU0_SA_DQ<27>")
		)
		(pad "188" smd rect
			(at 2.050034 -26.774902 90)
			(size 0.519938 1.4986)
			(layers "F.Cu" "F.Mask" "F.Paste")
			(net "GND")
		)
		(pad "189" smd rect
			(at 2.050034 -25.925018 90)
			(size 0.519938 1.4986)
			(layers "F.Cu" "F.Mask" "F.Paste")
			(net "M_H_CPU0_SA_DQS_DN<8>")
		)
		(pad "190" smd rect
			(at 2.050034 -25.07488 90)
			(size 0.519938 1.4986)
			(layers "F.Cu" "F.Mask" "F.Paste")
			(net "M_H_CPU0_SA_DQS_DP<8>")
		)
		(pad "191" smd rect
			(at 2.050034 -24.224996 90)
			(size 0.519938 1.4986)
			(layers "F.Cu" "F.Mask" "F.Paste")
			(net "GND")
		)
		(pad "192" smd rect
			(at 2.050034 -23.375112 90)
			(size 0.519938 1.4986)
			(layers "F.Cu" "F.Mask" "F.Paste")
			(net "M_H_CPU0_SA_DQ<30>")
		)
		(pad "193" smd rect
			(at 2.050034 -22.524974 90)
			(size 0.519938 1.4986)
			(layers "F.Cu" "F.Mask" "F.Paste")
			(net "GND")
		)
		(pad "194" smd rect
			(at 2.050034 -21.67509 90)
			(size 0.519938 1.4986)
			(layers "F.Cu" "F.Mask" "F.Paste")
			(net "M_H_CPU0_SA_DQ<31>")
		)
		(pad "195" smd rect
			(at 2.050034 -20.824952 90)
			(size 0.519938 1.4986)
			(layers "F.Cu" "F.Mask" "F.Paste")
			(net "GND")
		)
		(pad "196" smd rect
			(at 2.050034 -19.975068 90)
			(size 0.519938 1.4986)
			(layers "F.Cu" "F.Mask" "F.Paste")
			(net "M_H_CPU0_SA_CB<2>")
		)
		(pad "197" smd rect
			(at 2.050034 -19.12493 90)
			(size 0.519938 1.4986)
			(layers "F.Cu" "F.Mask" "F.Paste")
			(net "GND")
		)
		(pad "198" smd rect
			(at 2.050034 -18.275046 90)
			(size 0.519938 1.4986)
			(layers "F.Cu" "F.Mask" "F.Paste")
			(net "M_H_CPU0_SA_CB<3>")
		)
		(pad "199" smd rect
			(at 2.050034 -17.424908 90)
			(size 0.519938 1.4986)
			(layers "F.Cu" "F.Mask" "F.Paste")
			(net "GND")
		)
		(pad "200" smd rect
			(at 2.050034 -16.575024 90)
			(size 0.519938 1.4986)
			(layers "F.Cu" "F.Mask" "F.Paste")
			(net "M_H_CPU0_SA_DQS_DN<9>")
		)
		(pad "201" smd rect
			(at 2.050034 -15.724886 90)
			(size 0.519938 1.4986)
			(layers "F.Cu" "F.Mask" "F.Paste")
			(net "M_H_CPU0_SA_DQS_DP<9>")
		)
		(pad "202" smd rect
			(at 2.050034 -14.875002 90)
			(size 0.519938 1.4986)
			(layers "F.Cu" "F.Mask" "F.Paste")
			(net "GND")
		)
		(pad "203" smd rect
			(at 2.050034 -14.025118 90)
			(size 0.519938 1.4986)
			(layers "F.Cu" "F.Mask" "F.Paste")
			(net "M_H_CPU0_SA_CB<6>")
		)
		(pad "204" smd rect
			(at 2.050034 -13.17498 90)
			(size 0.519938 1.4986)
			(layers "F.Cu" "F.Mask" "F.Paste")
			(net "GND")
		)
		(pad "205" smd rect
			(at 2.050034 -12.325096 90)
			(size 0.519938 1.4986)
			(layers "F.Cu" "F.Mask" "F.Paste")
			(net "M_H_CPU0_SA_CB<7>")
		)
		(pad "206" smd rect
			(at 2.050034 -11.474958 90)
			(size 0.519938 1.4986)
			(layers "F.Cu" "F.Mask" "F.Paste")
			(net "GND")
		)
		(pad "207" smd rect
			(at 2.050034 -10.625074 90)
			(size 0.519938 1.4986)
			(layers "F.Cu" "F.Mask" "F.Paste")
			(net "M_H_CPU0_RESET_N")
		)
		(pad "208" smd rect
			(at 2.050034 -9.774936 90)
			(size 0.519938 1.4986)
			(layers "F.Cu" "F.Mask" "F.Paste")
			(net "GND")
		)
		(pad "209" smd rect
			(at 2.050034 -8.925052 90)
			(size 0.519938 1.4986)
			(layers "F.Cu" "F.Mask" "F.Paste")
			(net "M_H_CPU0_SA_CS_N<1>")
		)
		(pad "210" smd rect
			(at 2.050034 -8.074914 90)
			(size 0.519938 1.4986)
			(layers "F.Cu" "F.Mask" "F.Paste")
			(net "GND")
		)
		(pad "211" smd rect
			(at 2.050034 -7.22503 90)
			(size 0.519938 1.4986)
			(layers "F.Cu" "F.Mask" "F.Paste")
			(net "M_H_CPU0_SA_CA<1>")
		)
		(pad "212" smd rect
			(at 2.050034 -6.374892 90)
			(size 0.519938 1.4986)
			(layers "F.Cu" "F.Mask" "F.Paste")
			(net "GND")
		)
		(pad "213" smd rect
			(at 2.050034 -5.525008 90)
			(size 0.519938 1.4986)
			(layers "F.Cu" "F.Mask" "F.Paste")
			(net "M_H_CPU0_SA_CA<3>")
		)
		(pad "214" smd rect
			(at 2.050034 -4.675124 90)
			(size 0.519938 1.4986)
			(layers "F.Cu" "F.Mask" "F.Paste")
			(net "GND")
		)
		(pad "215" smd rect
			(at 2.050034 -3.824986 90)
			(size 0.519938 1.4986)
			(layers "F.Cu" "F.Mask" "F.Paste")
			(net "M_H_CPU0_SA_CA<5>")
		)
		(pad "216" smd rect
			(at 2.050034 -2.975102 90)
			(size 0.519938 1.4986)
			(layers "F.Cu" "F.Mask" "F.Paste")
			(net "GND")
		)
		(pad "217" smd rect
			(at 2.050034 -2.124964 90)
			(size 0.519938 1.4986)
			(layers "F.Cu" "F.Mask" "F.Paste")
			(net "M_H_CPU0_CLK_DP<0>")
		)
		(pad "218" smd rect
			(at 2.050034 -1.27508 90)
			(size 0.519938 1.4986)
			(layers "F.Cu" "F.Mask" "F.Paste")
			(net "M_H_CPU0_CLK_DN<0>")
		)
		(pad "219" smd rect
			(at 2.050034 -0.424942 90)
			(size 0.519938 1.4986)
			(layers "F.Cu" "F.Mask" "F.Paste")
			(net "GND")
		)
		(pad "220" smd rect
			(at 2.050034 5.525008 90)
			(size 0.519938 1.4986)
			(layers "F.Cu" "F.Mask" "F.Paste")
			(net "Net_2351")
		)
		(pad "221" smd rect
			(at 2.050034 6.374892 90)
			(size 0.519938 1.4986)
			(layers "F.Cu" "F.Mask" "F.Paste")
			(net "M_H_CPU0_SB_CA<1>")
		)
		(pad "222" smd rect
			(at 2.050034 7.22503 90)
			(size 0.519938 1.4986)
			(layers "F.Cu" "F.Mask" "F.Paste")
			(net "GND")
		)
		(pad "223" smd rect
			(at 2.050034 8.074914 90)
			(size 0.519938 1.4986)
			(layers "F.Cu" "F.Mask" "F.Paste")
			(net "M_H_CPU0_SB_CA<3>")
		)
		(pad "224" smd rect
			(at 2.050034 8.925052 90)
			(size 0.519938 1.4986)
			(layers "F.Cu" "F.Mask" "F.Paste")
			(net "GND")
		)
		(pad "225" smd rect
			(at 2.050034 9.774936 90)
			(size 0.519938 1.4986)
			(layers "F.Cu" "F.Mask" "F.Paste")
			(net "M_H_CPU0_SB_CA<5>")
		)
		(pad "226" smd rect
			(at 2.050034 10.625074 90)
			(size 0.519938 1.4986)
			(layers "F.Cu" "F.Mask" "F.Paste")
			(net "GND")
		)
		(pad "227" smd rect
			(at 2.050034 11.474958 90)
			(size 0.519938 1.4986)
			(layers "F.Cu" "F.Mask" "F.Paste")
			(net "M_H_CPU0_SB_PAR")
		)
		(pad "228" smd rect
			(at 2.050034 12.325096 90)
			(size 0.519938 1.4986)
			(layers "F.Cu" "F.Mask" "F.Paste")
			(net "GND")
		)
		(pad "229" smd rect
			(at 2.050034 13.17498 90)
			(size 0.519938 1.4986)
			(layers "F.Cu" "F.Mask" "F.Paste")
			(net "M_H_CPU0_SB_CS_N<1>")
		)
		(pad "230" smd rect
			(at 2.050034 14.025118 90)
			(size 0.519938 1.4986)
			(layers "F.Cu" "F.Mask" "F.Paste")
			(net "GND")
		)
	)
)
